(kicad_pcb
	(version 20241229)
	(generator "pcbnew")
	(generator_version "9.0")
	(general
		(thickness 1.61)
		(legacy_teardrops no)
	)
	(paper "A3")
	(title_block
		(title "SO-DIMM DDR5 Tester")
		(date "2025-11-26")
		(rev "1.3.0")
		(comment 9 "footprints 39-42 of 627")
	)
	(layers
		(0 "F.Cu" signal)
		(4 "In1.Cu" power)
		(6 "In2.Cu" mixed)
		(8 "In3.Cu" power)
		(10 "In4.Cu" mixed)
		(12 "In5.Cu" power)
		(14 "In6.Cu" mixed)
		(16 "In7.Cu" power)
		(18 "In8.Cu" power)
		(20 "In9.Cu" mixed)
		(22 "In10.Cu" power)
		(2 "B.Cu" signal)
		(9 "F.Adhes" user "F.Adhesive")
		(11 "B.Adhes" user "B.Adhesive")
		(13 "F.Paste" user)
		(15 "B.Paste" user)
		(5 "F.SilkS" user "F.Silkscreen")
		(7 "B.SilkS" user "B.Silkscreen")
		(1 "F.Mask" user)
		(3 "B.Mask" user)
		(17 "Dwgs.User" user "User.Drawings")
		(19 "Cmts.User" user "User.Comments")
		(21 "Eco1.User" user "User.Eco1")
		(23 "Eco2.User" user "User.Eco2")
		(25 "Edge.Cuts" user)
		(27 "Margin" user)
		(31 "F.CrtYd" user "F.Courtyard")
		(29 "B.CrtYd" user "B.Courtyard")
		(35 "F.Fab" user)
		(33 "B.Fab" user)
	)
	(footprint "antmicro-footprints:FB_0603_1608Metric"
		(layer "F.Cu")
		(at 104.500501 156.223149 180)
		(property "Reference" "FB6"
			(at 0 -0.8 180)
			(layer "F.SilkS")
			(hide yes)
			(effects
				(font
					(size 0.7 0.7)
					(thickness 0.15)
				)
				(justify left bottom)
			)
		)
		(property "Value" "FB_120Z_2A_Murata-BLM18PG_0603"
			(at 0 1.5 180)
			(layer "F.Fab")
			(effects
				(font
					(size 0.7 0.7)
					(thickness 0.15)
				)
				(justify left bottom)
			)
		)
		(property "Datasheet" "https://www.murata.com/en-us/products/productdata/8796738650142/ENFA0003.pdf"
			(at 0 0 180)
			(layer "F.Fab")
			(hide yes)
			(effects
				(font
					(size 1.27 1.27)
					(thickness 0.15)
				)
			)
		)
		(property "Author" "Antmicro"
			(at 209.001002 312.446298 0)
			(layer "F.Fab")
			(hide yes)
			(effects
				(font
					(size 1 1)
					(thickness 0.15)
				)
			)
		)
		(property "License" "Apache-2.0"
			(at 209.001002 312.446298 0)
			(layer "F.Fab")
			(hide yes)
			(effects
				(font
					(size 1 1)
					(thickness 0.15)
				)
			)
		)
		(property "MPN" "BLM18PG121SN1D"
			(at 209.001002 312.446298 0)
			(layer "F.Fab")
			(hide yes)
			(effects
				(font
					(size 1 1)
					(thickness 0.15)
				)
			)
		)
		(property "Manufacturer" "Murata"
			(at 209.001002 312.446298 0)
			(layer "F.Fab")
			(hide yes)
			(effects
				(font
					(size 1 1)
					(thickness 0.15)
				)
			)
		)
		(property "Val" "120Z/2A"
			(at 209.001002 312.446298 0)
			(layer "F.Fab")
			(hide yes)
			(effects
				(font
					(size 1 1)
					(thickness 0.15)
				)
			)
		)
		(sheetname "/Ethernet/")
		(sheetfile "ethernet.kicad_sch")
		(attr smd)
		(fp_line
			(start -0.196 0.406)
			(end 0.193 0.406)
			(stroke
				(width 0.15)
				(type solid)
			)
			(layer "F.SilkS")
		)
		(fp_line
			(start -0.196 -0.408)
			(end 0.193 -0.408)
			(stroke
				(width 0.15)
				(type solid)
			)
			(layer "F.SilkS")
		)
		(fp_rect
			(start -1.3 -0.6)
			(end 1.3 0.6)
			(stroke
				(width 0.05)
				(type solid)
			)
			(fill no)
			(layer "F.CrtYd")
		)
		(fp_line
			(start 0.8 0.406)
			(end -0.803 0.406)
			(stroke
				(width 0.15)
				(type solid)
			)
			(layer "F.Fab")
		)
		(fp_line
			(start 0.8 -0.408)
			(end 0.8 0.406)
			(stroke
				(width 0.15)
				(type solid)
			)
			(layer "F.Fab")
		)
		(fp_line
			(start 0.8 -0.408)
			(end -0.803 -0.408)
			(stroke
				(width 0.15)
				(type solid)
			)
			(layer "F.Fab")
		)
		(fp_line
			(start -0.803 0.406)
			(end -0.803 -0.408)
			(stroke
				(width 0.15)
				(type solid)
			)
			(layer "F.Fab")
		)
		(pad "1" smd roundrect
			(at -0.891 0 180)
			(size 0.762 1.09)
			(layers "F.Cu" "F.Mask" "F.Paste")
			(roundrect_rratio 0.15)
			(net 199 "+1V2")
			(pintype "passive")
		)
		(pad "2" smd roundrect
			(at 0.888 0 180)
			(size 0.762 1.09)
			(layers "F.Cu" "F.Mask" "F.Paste")
			(roundrect_rratio 0.15)
			(net 133 "/Ethernet/AVDDL_PLL")
			(pintype "passive")
		)
	)
	(footprint "antmicro-footprints:R_0402_1005Metric"
		(layer "F.Cu")
		(at 100.400501 151.358851 -90)
		(descr "Resistor SMD 0402")
		(tags "resistor SMD 0402")
		(property "Reference" "R112"
			(at -1.122484 -0.772697 270)
			(layer "F.SilkS")
			(hide yes)
			(effects
				(font
					(size 0.7 0.7)
					(thickness 0.15)
				)
				(justify left bottom)
			)
		)
		(property "Value" "R_12k1_0402"
			(at -1.011843 1.772047 270)
			(layer "F.Fab")
			(effects
				(font
					(size 0.7 0.7)
					(thickness 0.15)
				)
				(justify left bottom)
			)
		)
		(property "Datasheet" "https://www.bourns.com/docs/product-datasheets/cr.pdf"
			(at 0 0 270)
			(layer "F.Fab")
			(hide yes)
			(effects
				(font
					(size 1.27 1.27)
					(thickness 0.15)
				)
			)
		)
		(property "Author" "Antmicro"
			(at -50.95835 251.759352 0)
			(layer "F.Fab")
			(hide yes)
			(effects
				(font
					(size 1 1)
					(thickness 0.15)
				)
			)
		)
		(property "License" "Apache-2.0"
			(at -50.95835 251.759352 0)
			(layer "F.Fab")
			(hide yes)
			(effects
				(font
					(size 1 1)
					(thickness 0.15)
				)
			)
		)
		(property "MPN" "CR0402-FX-1212GLF"
			(at -50.95835 251.759352 0)
			(layer "F.Fab")
			(hide yes)
			(effects
				(font
					(size 1 1)
					(thickness 0.15)
				)
			)
		)
		(property "Manufacturer" "Bourns"
			(at -50.95835 251.759352 0)
			(layer "F.Fab")
			(hide yes)
			(effects
				(font
					(size 1 1)
					(thickness 0.15)
				)
			)
		)
		(property "Tolerance" "1%"
			(at -50.95835 251.759352 0)
			(layer "F.Fab")
			(hide yes)
			(effects
				(font
					(size 1 1)
					(thickness 0.15)
				)
			)
		)
		(property "Val" "12k1"
			(at -50.95835 251.759352 0)
			(layer "F.Fab")
			(hide yes)
			(effects
				(font
					(size 1 1)
					(thickness 0.15)
				)
			)
		)
		(sheetname "/Ethernet/")
		(sheetfile "ethernet.kicad_sch")
		(attr smd)
		(fp_rect
			(start -0.93 -0.47)
			(end 0.93 0.47)
			(stroke
				(width 0.05)
				(type solid)
			)
			(fill no)
			(layer "F.CrtYd")
		)
		(fp_rect
			(start -0.5 -0.25)
			(end 0.5 0.25)
			(stroke
				(width 0.15)
				(type solid)
			)
			(fill no)
			(layer "F.Fab")
		)
		(pad "1" smd roundrect
			(at -0.485 0 270)
			(size 0.59 0.64)
			(layers "F.Cu" "F.Mask" "F.Paste")
			(roundrect_rratio 0.25)
			(net 1 "GND")
			(pintype "passive")
		)
		(pad "2" smd roundrect
			(at 0.485 0 270)
			(size 0.59 0.64)
			(layers "F.Cu" "F.Mask" "F.Paste")
			(roundrect_rratio 0.25)
			(net 384 "Net-(U15-ISET)")
			(pintype "passive")
		)
	)
	(footprint "antmicro-footprints:R_0402_1005Metric"
		(layer "F.Cu")
		(at 100.400501 153.358851 90)
		(descr "Resistor SMD 0402")
		(tags "resistor SMD 0402")
		(property "Reference" "R100"
			(at -1.122484 -0.772697 90)
			(layer "F.SilkS")
			(hide yes)
			(effects
				(font
					(size 0.7 0.7)
					(thickness 0.15)
				)
				(justify left bottom)
			)
		)
		(property "Value" "R_1M8_0402"
			(at -1.011843 1.772047 90)
			(layer "F.Fab")
			(effects
				(font
					(size 0.7 0.7)
					(thickness 0.15)
				)
				(justify left bottom)
			)
		)
		(property "Datasheet" "https://www.mouser.com/catalog/specsheets/YAGEO_PYu_RC_Group_51_RoHS_L_12.pdf"
			(at 0 0 90)
			(layer "F.Fab")
			(hide yes)
			(effects
				(font
					(size 1.27 1.27)
					(thickness 0.15)
				)
			)
		)
		(property "Description" "SMD Chip Resistor"
			(at 0 0 90)
			(layer "F.Fab")
			(hide yes)
			(effects
				(font
					(size 1.27 1.27)
					(thickness 0.15)
				)
			)
		)
		(property "Author" "Antmicro"
			(at 253.759352 52.95835 0)
			(layer "F.Fab")
			(hide yes)
			(effects
				(font
					(size 1 1)
					(thickness 0.15)
				)
			)
		)
		(property "License" "Apache-2.0"
			(at 253.759352 52.95835 0)
			(layer "F.Fab")
			(hide yes)
			(effects
				(font
					(size 1 1)
					(thickness 0.15)
				)
			)
		)
		(property "MPN" "RC0402FR-071M8L"
			(at 253.759352 52.95835 0)
			(layer "F.Fab")
			(hide yes)
			(effects
				(font
					(size 1 1)
					(thickness 0.15)
				)
			)
		)
		(property "Manufacturer" "YAGEO"
			(at 253.759352 52.95835 0)
			(layer "F.Fab")
			(hide yes)
			(effects
				(font
					(size 1 1)
					(thickness 0.15)
				)
			)
		)
		(property "Tolerance" "1%"
			(at 253.759352 52.95835 0)
			(layer "F.Fab")
			(hide yes)
			(effects
				(font
					(size 1 1)
					(thickness 0.15)
				)
			)
		)
		(property "Val" "1M8"
			(at 253.759352 52.95835 0)
			(layer "F.Fab")
			(hide yes)
			(effects
				(font
					(size 1 1)
					(thickness 0.15)
				)
			)
		)
		(sheetname "/Ethernet/")
		(sheetfile "ethernet.kicad_sch")
		(attr smd)
		(fp_rect
			(start -0.93 -0.47)
			(end 0.93 0.47)
			(stroke
				(width 0.05)
				(type solid)
			)
			(fill no)
			(layer "F.CrtYd")
		)
		(fp_rect
			(start -0.5 -0.25)
			(end 0.5 0.25)
			(stroke
				(width 0.15)
				(type solid)
			)
			(fill no)
			(layer "F.Fab")
		)
		(pad "1" smd roundrect
			(at -0.485 0 90)
			(size 0.59 0.64)
			(layers "F.Cu" "F.Mask" "F.Paste")
			(roundrect_rratio 0.25)
			(net 300 "Net-(U15-XO)")
			(pintype "passive")
		)
		(pad "2" smd roundrect
			(at 0.485 0 90)
			(size 0.59 0.64)
			(layers "F.Cu" "F.Mask" "F.Paste")
			(roundrect_rratio 0.25)
			(net 299 "Net-(U15-XI)")
			(pintype "passive")
		)
	)
	(footprint "antmicro-footprints:Resonator_SMD_Abracon_ABM8G_3.2x2.5mm"
		(layer "F.Cu")
		(at 103.300501 152.558851)
		(property "Reference" "Y2"
			(at 0.799499 2.641149 180)
			(layer "F.SilkS")
			(effects
				(font
					(size 0.7 0.7)
					(thickness 0.15)
				)
				(justify left bottom)
			)
		)
		(property "Value" "Resonator_25MHz_ABM8G"
			(at -1.75 2.548 0)
			(layer "F.Fab")
			(effects
				(font
					(size 0.7 0.7)
					(thickness 0.15)
				)
				(justify left bottom)
			)
		)
		(property "Datasheet" "https://abracon.com/Resonators/ABM8G.pdf"
			(at 0 0 0)
			(layer "F.Fab")
			(hide yes)
			(effects
				(font
					(size 1.27 1.27)
					(thickness 0.15)
				)
			)
		)
		(property "Author" "Antmicro"
			(at 0 0 0)
			(layer "F.Fab")
			(hide yes)
			(effects
				(font
					(size 1 1)
					(thickness 0.15)
				)
			)
		)
		(property "License" "Apache-2.0"
			(at 0 0 0)
			(layer "F.Fab")
			(hide yes)
			(effects
				(font
					(size 1 1)
					(thickness 0.15)
				)
			)
		)
		(property "MPN" "ABM8G-25.000MHZ-18-D2Y-T3"
			(at 0 0 0)
			(layer "F.Fab")
			(hide yes)
			(effects
				(font
					(size 1 1)
					(thickness 0.15)
				)
			)
		)
		(property "Manufacturer" "Abracon"
			(at 0 0 0)
			(layer "F.Fab")
			(hide yes)
			(effects
				(font
					(size 1 1)
					(thickness 0.15)
				)
			)
		)
		(property "Val" "25 MHz"
			(at 0 0 0)
			(layer "F.Fab")
			(hide yes)
			(effects
				(font
					(size 1 1)
					(thickness 0.15)
				)
			)
		)
		(sheetname "/Ethernet/")
		(sheetfile "ethernet.kicad_sch")
		(attr smd)
		(fp_line
			(start -1.6 0.3)
			(end -1.6 -0.2)
			(stroke
				(width 0.15)
				(type solid)
			)
			(layer "F.SilkS")
		)
		(fp_line
			(start -0.35 -1.25)
			(end 0.45 -1.25)
			(stroke
				(width 0.15)
				(type solid)
			)
			(layer "F.SilkS")
		)
		(fp_line
			(start -0.35 1.25)
			(end 0.45 1.25)
			(stroke
				(width 0.15)
				(type solid)
			)
			(layer "F.SilkS")
		)
		(fp_line
			(start 1.6 0.3)
			(end 1.6 -0.2)
			(stroke
				(width 0.15)
				(type solid)
			)
			(layer "F.SilkS")
		)
		(fp_circle
			(center -1.75 1.5)
			(end -1.7 1.5)
			(stroke
				(width 0.15)
				(type solid)
			)
			(fill no)
			(layer "F.SilkS")
		)
		(fp_rect
			(start -1.907 -1.55)
			(end 2.006 1.649)
			(stroke
				(width 0.05)
				(type solid)
			)
			(fill no)
			(layer "F.CrtYd")
		)
		(pad "1" smd roundrect
			(at -1.101 0.949)
			(size 1.3 1.1)
			(layers "F.Cu" "F.Mask" "F.Paste")
			(roundrect_rratio 0)
			(chamfer_ratio 0.2)
			(chamfer bottom_left)
			(net 300 "Net-(U15-XO)")
			(pintype "passive")
		)
		(pad "2" smd rect
			(at 1.199 0.949)
			(size 1.3 1.1)
			(layers "F.Cu" "F.Mask" "F.Paste")
			(net 1 "GND")
			(pinfunction "SH")
			(pintype "passive")
		)
		(pad "3" smd rect
			(at 1.199 -0.85)
			(size 1.3 1.1)
			(layers "F.Cu" "F.Mask" "F.Paste")
			(net 299 "Net-(U15-XI)")
			(pintype "passive")
		)
		(pad "4" smd rect
			(at -1.101 -0.85)
			(size 1.3 1.1)
			(layers "F.Cu" "F.Mask" "F.Paste")
			(net 1 "GND")
			(pinfunction "SH")
			(pintype "passive")
		)
	)
)
